FILE_TYPE = MULTI_PHYS_TABLE;

PART 'Q_CRYSTAL'

{========================================================================================}
:VALUE         | PACK_TYPE | MATERIAL | PART_NUMBER           = PART_NUMBER        | JEDEC_TYPE   | CLASS | DESCRIPTION                                | HEIGHT   | COMPONENT_TYPE | LEAD_LENGTH | DAY         ;
{========================================================================================}
 '30MHz'       | 'SM'      | 'IC'     | 'TMP_QBG630000103'(!) = 'BG630000103' | 'X_6X'     | 'IC'  | 'XTAL SMD 30MHZ(+-30PPM,16PF)6X30000010'   | '.060IN' | 'SMTOTHER'     | ''          | ''         
 '30MHz'       | 'SM'      | 'EMPTY'  | 'TMP_QBG630000103'(!) = 'BG630000103' | 'X_6X'     | 'IO'  | 'XTAL SMD 30MHZ(+-30PPM,16PF)6X30000010'   | '.060IN' | 'SMTOTHER'     | ''          | ''         
 '24.576MHZ'   | 'SM'      | 'IC'     | 'TMP_QBG624576465'(!) = 'BG624576465' | 'X_6X'     | 'IC'  | 'XTAL SMD 24.576MHZ(+-30PPM)6X24500072'    | '.060IN' | 'SMTOTHER'     | ''          | ''         
 '24.576MHZ'   | 'SM'      | 'EMPTY'  | 'TMP_QBG624576465'(!) = 'BG624576465' | 'X_6X'     | 'IO'  | 'XTAL SMD 24.576MHZ(+-30PPM)6X24500072'    | '.060IN' | 'SMTOTHER'     | ''          | ''         
 '18.432MHZ'   | 'SM'      | 'IC'     | 'TMP_QBG618432601'(!) = 'BG618432601' | 'X_F8_H67' | 'IC'  | 'XTAL SMD 18.432 MHZ(+-30PPM,F81840002)'   | '.067IN' | 'SMTOTHER'     | ''          | ''         
 '18.432MHZ'   | 'SM'      | 'EMPTY'  | 'TMP_QBG618432601'(!) = 'BG618432601' | 'X_F8_H67' | 'IO'  | 'XTAL SMD 18.432 MHZ(+-30PPM,F81840002)'   | '.067IN' | 'SMTOTHER'     | ''          | ''         
 '14.318MHZ'   | 'SM'      | 'IC'     | 'QN-BG614318Q25'(!) = 'BG614318Q25'   | 'X_6XXA'     | 'IC'  | 'XTAL SMD 14.318MHZ(+-20PPM,20PF)'         | '.056IN' | 'SMTOTHER'     | ''          | ''         
 '14.318MHZ'   | 'SM'      | 'EMPTY'  | 'QN-BG614318Q25'(!) = 'BG614318Q25'   | 'X_6XXA'     | 'IO'  | 'XTAL SMD 14.318MHZ(+-20PPM,20PF)'         | '.056IN' | 'SMTOTHER'     | ''          | ''         
 '25MHZ'       | 'SM'      | 'IC'     | 'QN-BG625000435'(!) = 'BG625000435'   | 'X_HC49A'    | 'IC'  | 'CRYSTAL SMD 25MHZ(+-30PPM,9C25000355)'    | '.162IN' | 'SMTOTHER'     | ''          | ''         
 '25MHZ'       | 'SM'      | 'EMPTY'  | 'QN-BG625000435'(!) = 'BG625000435'   | 'X_HC49A'    | 'IO'  | 'CRYSTAL SMD 25MHZ(+-30PPM,9C25000355)'    | '.162IN' | 'SMTOTHER'     | ''          | ''         
 '14.31818MHz' | 'SM'      | 'IC'     | 'BG614318S11'(!)   = 'BG614318S11'      | 'X_HC49A'    | 'IC'  | 'XTAL SMD 14.318MHZ(+-30PPM,9C14300040)LF' | '.162IN' | 'SMTOTHER'     | ''          | '20100714' 
 '14.31818MHz' | 'SM'      | 'EMPTY'  | 'BG614318S11'(!)   = 'BG614318S11'      | 'X_HC49A'    | 'IO'  | 'XTAL SMD 14.318MHZ(+-30PPM,9C14300040)LF' | '.162IN' | 'SMTOTHER'     | ''          | '20100714' 
 '50MHZ'       | 'SM'      | 'IC'     | 'BG650000003'(!)   = 'BG650000003'      | 'X_7A'       | 'IC'  | 'XTAL SMD 50MHZ(+-15PPM,16PF)7A50020001'   | '.054IN' | 'SMTOTHER'     | ''          | '20110211' 
 '50MHZ'       | 'SM'      | 'EMPTY'  | 'BG650000003'(!)   = 'BG650000003'      | 'X_7A'       | 'IO'  | 'XTAL SMD 50MHZ(+-15PPM,16PF)7A50020001'   | '.054IN' | 'SMTOTHER'     | ''          | '20110211' 
 '48MHZ'       | 'SMLF'    | 'IC'     | 'BG648000010'(!)   = 'BG648000010'      | 'X_7A'       | 'IC'  | 'XTAL SMD 48MHZ(+-20PPM,12PF)7A48000065'   | '.054IN' | 'SMTOTHER'     | ''          | '2011/3/24'
 '48MHZ'       | 'SMLF'    | 'EMPTY'  | 'BG648000010'(!)   = 'BG648000010'      | 'X_7A'       | 'IO'  | 'XTAL SMD 48MHZ(+-20PPM,12PF)7A48000065'   | '.054IN' | 'SMTOTHER'     | ''          | '2011/3/24'
 '6MHz'        | 'SMLF'    | 'IC'     | 'BG560000001'(!)   = 'BG560000001'      | 'X_HC49A'    | 'IC'  | 'CRYSTAL SMD 6MHZ(20PF+-30PPM0)9C06000077' | '.162IN' | 'SMTOTHER'     | ''          | '20111209' 
 '6MHz'        | 'SMLF'    | 'EMPTY'  | 'BG560000001'(!)   = 'BG560000001'      | 'X_HC49A'    | 'IO'  | 'CRYSTAL SMD 6MHZ(20PF+-30PPM0)9C06000077' | '.162IN' | 'SMTOTHER'     | ''          | '20111209' 
 '12MHz'       | 'SMLF'    | 'IC'     | 'BG612000009'(!)   = 'BG612000009'      | 'X_HC49XA'   | 'IC'  | 'XTAL 12MHZ(30PPM.20PF)ESB12.0000F20E35F'  | '.166IN' | 'SMTOTHER'     | ''          | '20111209' 
 '12MHz'       | 'SMLF'    | 'EMPTY'  | 'BG612000009'(!)   = 'BG612000009'      | 'X_HC49XA'   | 'IO'  | 'XTAL 12MHZ(30PPM.20PF)ESB12.0000F20E35F'  | '.166IN' | 'SMTOTHER'     | ''          | '20111209' 
 '12MHz'       | 'SMLF'    | 'IC'     | 'BG612000334'(!)   = 'BG612000334'      | 'X_7A'       | 'IC'  | 'XTAL SMD 12MHZ(+-30PPM,16PF)7A12000017'   | '.054IN' | 'SMTOTHER'     | ''          | '20120109' 
 '12MHz'       | 'SMLF'    | 'EMPTY'  | 'BG612000334'(!)   = 'BG612000334'      | 'X_7A'       | 'IO'  | 'XTAL SMD 12MHZ(+-30PPM,16PF)7A12000017'   | '.054IN' | 'SMTOTHER'     | ''          | '20120109' 
 '32.768KHZ'   | 'SMLF'    | 'IC'     | 'BG332768066'(!)   = 'BG332768066'      | 'X_2S_XTL721' | 'IC'  | 'XTAL SMD 32.768KHZ(20PPM,12.5PF)XTL721'   | '.036IN' | 'SMTOTHER'     | ''          | '20120525' 
 '32.768KHZ'   | 'SMLF'    | 'EMPTY'  | 'BG332768066'(!)   = 'BG332768066'      | 'X_2S_XTL721' | 'IO'  | 'XTAL SMD 32.768KHZ(20PPM,12.5PF)XTL721'   | '.036IN' | 'SMTOTHER'     | ''          | '20120525' 
 '32.768KHZ'   | 'SMLF'    | 'IC'     | 'BG332768064'(!)   = 'BG332768064'      | 'X_2S_FC145'  | 'IC'  | 'XTAL 32.768KHZ(+0PPM-20PPM,12.5PF)'       | '.036IN' | 'SMTOTHER'     | ''          | '20120712' 
 '32.768KHZ'   | 'SMLF'    | 'EMPTY'  | 'BG332768064'(!)   = 'BG332768064'      | 'X_2S_FC145'  | 'IO'  | 'XTAL 32.768KHZ(+0PPM-20PPM,12.5PF)'       | '.036IN' | 'SMTOTHER'     | ''          | '20120712' 
 '32.768KHZ'   | 'SMLF'    | 'IC'     | 'BG332768453'(!)   = 'BG332768453'      | 'X_2S_FC145'  | 'IC'  | 'CRYSTAL SMD 32.768KHZ(+-20PPM,12.5PF)'    | '.036IN' | 'SMTOTHER'     | ''          | '20120712' 
 '32.768KHZ'   | 'SMLF'    | 'EMPTY'  | 'BG332768453'(!)   = 'BG332768453'      | 'X_2S_FC145'  | 'IO'  | 'CRYSTAL SMD 32.768KHZ(+-20PPM,12.5PF)'    | '.036IN' | 'SMTOTHER'     | ''          | '20120712' 

 '32.768KHZ'   | 'SMLF'    | 'IC'     | 'BG332768077'(!)   = 'BG332768077'      | 'X_2S_XTL721'  | 'IC'  | 'CRYSTAL SMD 32.768KHZ(+-20PPM,12.5PF)'    | '.036IN' | 'SMTOTHER'     | ''          | '20120917' 
 '32.768KHZ'   | 'SMLF'    | 'EMPTY'  | 'BG332768077'(!)   = 'BG332768077'      | 'X_2S_XTL721'  | 'IO'  | 'CRYSTAL SMD 32.768KHZ(+-20PPM,12.5PF)'    | '.036IN' | 'SMTOTHER'     | ''          | '20120917' 


END_PART

END.

